FILE_TYPE = CONNECTIVITY;
{Allegro Design Entry HDL 17.2-2016 S081 (4005846) 1/11/2022}
"PAGE_NUMBER" = 121;
0"NC";
1"PVNN_TERM_CPU1\g";
2"PVNN_TERM_CPU1\g";
3"PVNN_TERM_CPU0\g";
4"PVNN_TERM_CPU0\g";
5"PVNN_TERM_CPU1\g";
6"PVNN_TERM_CPU0\g";
7"P3V3\g";
8"P3V3\g";
9"GND\g";
10"GND\g";
11"H_CPU0_THERMTRIP_LVC1_N";
12"H_CPU0_THERMTRIP_VT_N";
13"H_CPU0_THERMTRIP_R_N";
14"H_CPU1_THERMTRIP_LVC1_N";
15"H_CPU1_THERMTRIP_VT_N";
16"H_CPU1_THERMTRIP_R_N";
17"H_CPU0_PROCHOT_LVC1_N";
18"H_CPU1_PROCHOT_LVC1_N";
19"H_CPU0_THERMTRIP_N";
20"H_CPU0_THERMTRIP_VT_R_N";
21"H_CPU0_THERMTRIP_LVC1_R_N";
22"H_CPU1_THERMTRIP_N";
23"H_CPU1_THERMTRIP_VT_R_N";
24"H_CPU1_PROCHOT_LVC1_R_N";
25"H_CPU0_PROCHOT_LVC1_R_N";
26"H_CPU1_THERMTRIP_LVC1_R_N";
%"Q_RES"
"1","(100,600)","0","pure_quanta","I10";
;
PART_NUMBER"CS21502FB07"
VALUE"1.5K"
MATERIAL"CHIP"
PACK_TYPE"0402LF"
$LOCATION"R4398"
WATTAGE"1/16W"
TOLERANCE"1%"
CDS_LIB"pure_quanta"
CDS_LOCATION"R4398"
$SEC"1"
CDS_SEC"1";
"B"
$PN"2"16;
"A"
$PN"1"22;
%"UNIVERSAL_POWER"
"1","(-2025,1325)","0","logical_power","I12";
;
HDL_POWER"PVNN_TERM_CPU1"
CDS_LIB"logical_power";
"A"2;
%"Q_RES"
"2","(-2025,2475)","0","pure_quanta","I13";
;
PART_NUMBER"CS11002FB07"
WATTAGE"1/16W"
VALUE"100"
TOLERANCE"1%"
MATERIAL"CHIP"
PACK_TYPE"0402LF"
$LOCATION"R4395"
CDS_LIB"pure_quanta"
CDS_LOCATION"R4395"
$SEC"1"
CDS_SEC"1";
"A"
$PN"1"3;
"B"
$PN"2"21;
%"UNIVERSAL_POWER"
"1","(-2025,2675)","0","logical_power","I14";
;
HDL_POWER"PVNN_TERM_CPU0"
CDS_LIB"logical_power";
"A"3;
%"Q_RES"
"1","(-1650,2200)","0","pure_quanta","I15";
;
PART_NUMBER"CS21502FB07"
VALUE"1.5K"
WATTAGE"1/16W"
TOLERANCE"1%"
MATERIAL"CHIP"
PACK_TYPE"0402LF"
LOCATION"R237"
CDS_LIB"pure_quanta"
$SEC"1"
CDS_SEC"1";
"B"
$PN"2"20;
"A"
$PN"1"21;
%"Q_RES"
"1","(100,1950)","0","pure_quanta","I16";
;
PART_NUMBER"CS21502FB07"
MATERIAL"CHIP"
PACK_TYPE"0402LF"
VALUE"1.5K"
$LOCATION"R4397"
WATTAGE"1/16W"
TOLERANCE"1%"
CDS_LIB"pure_quanta"
CDS_LOCATION"R4397"
$SEC"1"
CDS_SEC"1";
"B"
$PN"2"13;
"A"
$PN"1"19;
%"BC847BPN"
"2","(-675,2200)","0","pure_quanta","I17";
;
PART_NUMBER"BA008470026"
VALUE"BC847BPN"
MATERIAL"IC"
PART_TYPE"SMLF"
LOCATION"Q138"
CDS_LMAN_SYM_OUTLINE"-50,50,50,-50"
NEEDS_NO_SIZE"TRUE"
CDS_LIB"pure_quanta"
$SEC"2"
CDS_SEC"2";
"E2"
$PN"4"4;
"C2"
$PN"3"19;
"B2"
$PN"5"20;
%"UNIVERSAL_POWER"
"1","(-625,2450)","0","logical_power","I18";
;
HDL_POWER"PVNN_TERM_CPU0"
CDS_LIB"logical_power";
"A"4;
%"Q_RES"
"2","(1450,-1225)","0","pure_quanta","I19";
;
PART_NUMBER"CS11002FB07"
PACK_TYPE"0402LF"
VALUE"100"
TOLERANCE"1%"
WATTAGE"1/16W"
MATERIAL"CHIP"
$LOCATION"R244"
CDS_LIB"pure_quanta"
CDS_LOCATION"R244"
$SEC"1"
CDS_SEC"1";
"A"
$PN"1"5;
"B"
$PN"2"18;
%"UNIVERSAL_POWER"
"1","(1450,-975)","0","logical_power","I20";
;
HDL_POWER"PVNN_TERM_CPU1"
CDS_LIB"logical_power";
"A"5;
%"BC847BPN"
"1","(875,600)","0","pure_quanta","I21";
;
PART_NUMBER"BA008470026"
VALUE"BC847BPN"
PART_TYPE"SMLF"
MATERIAL"IC"
LOCATION"Q139"
CDS_LMAN_SYM_OUTLINE"-50,50,50,-50"
NEEDS_NO_SIZE"TRUE"
CDS_LIB"pure_quanta"
$SEC"1"
CDS_SEC"1";
"E1"
$PN"1"9;
"C1"
$PN"6"15;
"B1"
$PN"2"16;
%"UNIVERSAL_GND"
"1","(975,925)","0","logical_power","I22";
;
HDL_POWER"GND"
CDS_LIB"logical_power";
"A"9;
%"Q_RES"
"2","(1450,-325)","0","pure_quanta","I23";
;
PART_NUMBER"CS11002FB07"
PACK_TYPE"0402LF"
TOLERANCE"1%"
VALUE"100"
WATTAGE"1/16W"
MATERIAL"CHIP"
$LOCATION"R243"
CDS_LIB"pure_quanta"
CDS_LOCATION"R243"
$SEC"1"
CDS_SEC"1";
"A"
$PN"1"6;
"B"
$PN"2"17;
%"UNIVERSAL_POWER"
"1","(1450,-75)","0","logical_power","I24";
;
HDL_POWER"PVNN_TERM_CPU0"
CDS_LIB"logical_power";
"A"6;
%"UNIVERSAL_POWER"
"1","(1725,1000)","0","logical_power","I25";
;
HDL_POWER"P3V3"
CDS_LIB"logical_power";
"A"7;
%"Q_RES"
"2","(1725,750)","0","pure_quanta","I26";
;
PART_NUMBER"CS24752FB03"
WATTAGE"1/16W"
MATERIAL"CHIP"
TOLERANCE"1%"
VALUE"4.75K"
PACK_TYPE"0402LF"
LOCATION"R242"
CDS_LIB"pure_quanta"
$SEC"1"
CDS_SEC"1";
"A"
$PN"1"7;
"B"
$PN"2"15;
%"Q_RES"
"1","(2375,375)","0","pure_quanta","I29";
;
PART_NUMBER"CS03322FB03"
VALUE"33.2"
PACK_TYPE"0402LF"
MATERIAL"CHIP"
TOLERANCE"1%"
WATTAGE"1/16W"
$LOCATION"R4400"
CDS_LIB"pure_quanta"
CDS_LOCATION"R4400"
$SEC"1"
CDS_SEC"1";
"B"
$PN"2"14;
"A"
$PN"1"15;
%"BC847BPN"
"1","(875,1950)","0","pure_quanta","I31";
;
PART_NUMBER"BA008470026"
VALUE"BC847BPN"
MATERIAL"IC"
PART_TYPE"SMLF"
LOCATION"Q138"
CDS_LMAN_SYM_OUTLINE"-50,50,50,-50"
NEEDS_NO_SIZE"TRUE"
CDS_LIB"pure_quanta"
$SEC"1"
CDS_SEC"1";
"E1"
$PN"1"10;
"C1"
$PN"6"12;
"B1"
$PN"2"13;
%"UNIVERSAL_GND"
"1","(975,2275)","0","logical_power","I32";
;
HDL_POWER"GND"
CDS_LIB"logical_power";
"A"10;
%"Q_RES"
"2","(1725,2100)","0","pure_quanta","I33";
;
PART_NUMBER"CS24752FB03"
WATTAGE"1/16W"
MATERIAL"CHIP"
TOLERANCE"1%"
VALUE"4.75K"
PACK_TYPE"0402LF"
$LOCATION"R241"
CDS_LIB"pure_quanta"
CDS_LOCATION"R241"
$SEC"1"
CDS_SEC"1";
"A"
$PN"1"8;
"B"
$PN"2"12;
%"UNIVERSAL_POWER"
"1","(1725,2350)","0","logical_power","I34";
;
HDL_POWER"P3V3"
CDS_LIB"logical_power";
"A"8;
%"Q_RES"
"1","(2375,1725)","0","pure_quanta","I35";
;
PART_NUMBER"CS03322FB03"
VALUE"33.2"
TOLERANCE"1%"
WATTAGE"1/16W"
PACK_TYPE"0402LF"
MATERIAL"CHIP"
$LOCATION"R4399"
CDS_LIB"pure_quanta"
CDS_LOCATION"R4399"
$SEC"1"
CDS_SEC"1";
"B"
$PN"2"11;
"A"
$PN"1"12;
%"Q_RES"
"2","(-2025,1125)","0","pure_quanta","I4";
;
PART_NUMBER"CS11002FB07"
VALUE"100"
TOLERANCE"1%"
MATERIAL"CHIP"
WATTAGE"1/16W"
PACK_TYPE"0402LF"
$LOCATION"R4396"
CDS_LIB"pure_quanta"
CDS_LOCATION"R4396"
$SEC"1"
CDS_SEC"1";
"A"
$PN"1"2;
"B"
$PN"2"26;
%"Q_RES"
"1","(-725,-1475)","0","pure_quanta","I5";
;
PART_NUMBER"CS00002JB13"
TOLERANCE"5%"
MATERIAL"CHIP"
PACK_TYPE"0402LF"
VALUE"0"
WATTAGE"1/16W"
$LOCATION"R240"
CDS_LIB"pure_quanta"
CDS_LOCATION"R240"
$SEC"1"
CDS_SEC"1";
"B"
$PN"2"18;
"A"
$PN"1"24;
%"Q_RES"
"1","(-1650,850)","0","pure_quanta","I6";
;
PART_NUMBER"CS21502FB07"
PACK_TYPE"0402LF"
VALUE"1.5K"
TOLERANCE"1%"
MATERIAL"CHIP"
WATTAGE"1/16W"
LOCATION"R238"
CDS_LIB"pure_quanta"
$SEC"1"
CDS_SEC"1";
"B"
$PN"2"23;
"A"
$PN"1"26;
%"Q_RES"
"1","(-725,-575)","0","pure_quanta","I7";
;
PART_NUMBER"CS00002JB13"
MATERIAL"CHIP"
WATTAGE"1/16W"
PACK_TYPE"0402LF"
TOLERANCE"5%"
VALUE"0"
$LOCATION"R239"
CDS_LIB"pure_quanta"
CDS_LOCATION"R239"
$SEC"1"
CDS_SEC"1";
"B"
$PN"2"17;
"A"
$PN"1"25;
%"BC847BPN"
"2","(-675,850)","0","pure_quanta","I8";
;
PART_NUMBER"BA008470026"
VALUE"BC847BPN"
MATERIAL"IC"
PART_TYPE"SMLF"
LOCATION"Q139"
CDS_LMAN_SYM_OUTLINE"-50,50,50,-50"
NEEDS_NO_SIZE"TRUE"
CDS_LIB"pure_quanta"
$SEC"2"
CDS_SEC"2";
"E2"
$PN"4"1;
"C2"
$PN"3"22;
"B2"
$PN"5"23;
%"UNIVERSAL_POWER"
"1","(-625,1100)","0","logical_power","I9";
;
HDL_POWER"PVNN_TERM_CPU1"
CDS_LIB"logical_power";
"A"1;
END.
